# T6G (Grand Teton) — schematic netlist excerpt (pin names and nets, part order shuffled) for the footprints in the layout excerpt that follows; sources: Cadence DE-HDL packaged netlist, KiCad conversion of 04192023_DAF0TMB3IC0_F0TG_MB_C_brd_V02_OCP.brd

PC1867  Q_CAPP  560UF 6.3V 20% OSCON  pkg THLF  page 190 : A = P3V3_AUX ; B = GND
PR35  Q_RES  0 5% CHIP  pkg 0402LF  page 207 : A = NC_PVDD11_S3_P0_IMON6 ; B = GND
R3784  Q_RES  0 5% CHIP  pkg 0402LF  page 134 : A = P12V_OCP_UV_1_R ; B = P12V_OCP_UV_1

(kicad_pcb
	(version 20260206)
	(generator "pcbnew")
	(generator_version "10.0")
	(general
		(thickness 1.6)
		(legacy_teardrops no)
	)
	(paper "A4")
	(title_block
		(title "04192023_DAF0TMB3IC0_F0TG_MB_C_brd_V02_OCP.brd")
		(comment 1 "Grand Teton / footprints 916-918 of 8354")
	)
	(layers
		(0 "F.Cu" signal "TOP")
		(4 "In1.Cu" signal "GND")
		(6 "In2.Cu" signal "IN1")
		(8 "In3.Cu" signal "GND1")
		(10 "In4.Cu" signal "IN2")
		(12 "In5.Cu" signal "GND2")
		(14 "In6.Cu" signal "IN3")
		(16 "In7.Cu" signal "GND3")
		(18 "In8.Cu" signal "VCC")
		(20 "In9.Cu" signal "VCC1")
		(22 "In10.Cu" signal "GND4")
		(24 "In11.Cu" signal "IN4")
		(26 "In12.Cu" signal "GND5")
		(28 "In13.Cu" signal "IN5")
		(30 "In14.Cu" signal "GND6")
		(32 "In15.Cu" signal "IN6")
		(34 "In16.Cu" signal "GND7")
		(2 "B.Cu" signal "BOTTOM")
		(9 "F.Adhes" user "F.Adhesive")
		(11 "B.Adhes" user "B.Adhesive")
		(13 "F.Paste" user "Package Geometry/Pastemask Top")
		(15 "B.Paste" user "Package Geometry/Pastemask Bottom")
		(5 "F.SilkS" user "Ref Des/Silkscreen Top")
		(7 "B.SilkS" user "Ref Des/Silkscreen Bottom")
		(1 "F.Mask" user "Board Geometry/Soldermask Top")
		(3 "B.Mask" user "Board Geometry/Soldermask Bottom")
		(17 "Dwgs.User" user "User.Drawings")
		(19 "Cmts.User" user "User.Comments")
		(21 "Eco1.User" user "User.Eco1")
		(23 "Eco2.User" user "User.Eco2")
		(25 "Edge.Cuts" user "Board Geometry/Outline")
		(27 "Margin" user)
		(31 "F.CrtYd" user "Package Geometry/Place Bound Top")
		(29 "B.CrtYd" user "Package Geometry/Place Bound Bottom")
		(35 "F.Fab" user "Ref Des/Assembly Top")
		(33 "B.Fab" user "Ref Des/Assembly Bottom")
	)
	(footprint ""
		(layer "F.Cu")
		(at 421.798496 -357.688134 -90)
		(property "Reference" "PR35"
			(at 0 0 270)
			(layer "F.SilkS")
			(hide yes)
			(effects
				(font
					(size 1.27 1.27)
				)
			)
		)
		(property "Value" ""
			(at 0 0 270)
			(layer "F.Fab")
			(effects
				(font
					(size 1.27 1.27)
				)
			)
		)
		(duplicate_pad_numbers_are_jumpers no)
		(fp_line
			(start -0.7874 0.4064)
			(end -0.7874 -0.4064)
			(stroke
				(width 0.1524)
				(type default)
			)
			(layer "F.SilkS")
		)
		(fp_line
			(start 0.7874 0.4064)
			(end -0.7874 0.4064)
			(stroke
				(width 0.1524)
				(type default)
			)
			(layer "F.SilkS")
		)
		(fp_line
			(start -0.7874 -0.4064)
			(end 0.7874 -0.4064)
			(stroke
				(width 0.1524)
				(type default)
			)
			(layer "F.SilkS")
		)
		(fp_line
			(start 0.7874 -0.4064)
			(end 0.7874 0.4064)
			(stroke
				(width 0.1524)
				(type default)
			)
			(layer "F.SilkS")
		)
		(fp_line
			(start -0.67945 0.3048)
			(end -0.67945 -0.305054)
			(stroke
				(width 0.1)
				(type default)
			)
			(layer "F.Fab")
		)
		(fp_line
			(start -0.12065 0.3048)
			(end -0.67945 0.3048)
			(stroke
				(width 0.1)
				(type default)
			)
			(layer "F.Fab")
		)
		(fp_line
			(start 0.120396 0.3048)
			(end 0.120396 0.2794)
			(stroke
				(width 0.1)
				(type default)
			)
			(layer "F.Fab")
		)
		(fp_line
			(start 0.67945 0.3048)
			(end 0.120396 0.3048)
			(stroke
				(width 0.1)
				(type default)
			)
			(layer "F.Fab")
		)
		(fp_line
			(start -0.12065 0.2794)
			(end -0.12065 0.3048)
			(stroke
				(width 0.1)
				(type default)
			)
			(layer "F.Fab")
		)
		(fp_line
			(start 0.120396 0.2794)
			(end -0.12065 0.2794)
			(stroke
				(width 0.1)
				(type default)
			)
			(layer "F.Fab")
		)
		(fp_line
			(start -0.12065 -0.2794)
			(end 0.12065 -0.2794)
			(stroke
				(width 0.1)
				(type default)
			)
			(layer "F.Fab")
		)
		(fp_line
			(start 0.12065 -0.2794)
			(end 0.12065 -0.3048)
			(stroke
				(width 0.1)
				(type default)
			)
			(layer "F.Fab")
		)
		(fp_line
			(start 0.12065 -0.3048)
			(end 0.67945 -0.3048)
			(stroke
				(width 0.1)
				(type default)
			)
			(layer "F.Fab")
		)
		(fp_line
			(start 0.67945 -0.3048)
			(end 0.67945 0.3048)
			(stroke
				(width 0.1)
				(type default)
			)
			(layer "F.Fab")
		)
		(fp_line
			(start -0.67945 -0.305054)
			(end -0.12065 -0.305054)
			(stroke
				(width 0.1)
				(type default)
			)
			(layer "F.Fab")
		)
		(fp_line
			(start -0.12065 -0.305054)
			(end -0.12065 -0.2794)
			(stroke
				(width 0.1)
				(type default)
			)
			(layer "F.Fab")
		)
		(pad "1" smd circle
			(at -0.40005 0 270)
			(size 0 0)
			(layers "F.Cu" "F.Mask" "F.Paste")
			(net "NC_PVDD11_S3_P0_IMON6")
		)
		(pad "2" smd circle
			(at 0.40005 0 270)
			(size 0 0)
			(layers "F.Cu" "F.Mask" "F.Paste")
			(net "GND")
		)
	)
	(footprint ""
		(layer "F.Cu")
		(at 455.01306 -39.835836 180)
		(property "Reference" "R3784"
			(at 0 0 180)
			(layer "F.SilkS")
			(hide yes)
			(effects
				(font
					(size 1.27 1.27)
				)
			)
		)
		(property "Value" ""
			(at 0 0 180)
			(layer "F.Fab")
			(effects
				(font
					(size 1.27 1.27)
				)
			)
		)
		(duplicate_pad_numbers_are_jumpers no)
		(fp_line
			(start 0.7874 0.4064)
			(end -0.7874 0.4064)
			(stroke
				(width 0.1524)
				(type default)
			)
			(layer "F.SilkS")
		)
		(fp_line
			(start 0.7874 -0.4064)
			(end 0.7874 0.4064)
			(stroke
				(width 0.1524)
				(type default)
			)
			(layer "F.SilkS")
		)
		(fp_line
			(start -0.7874 0.4064)
			(end -0.7874 -0.4064)
			(stroke
				(width 0.1524)
				(type default)
			)
			(layer "F.SilkS")
		)
		(fp_line
			(start -0.7874 -0.4064)
			(end 0.7874 -0.4064)
			(stroke
				(width 0.1524)
				(type default)
			)
			(layer "F.SilkS")
		)
		(fp_line
			(start 0.67945 0.3048)
			(end 0.120396 0.3048)
			(stroke
				(width 0.1)
				(type default)
			)
			(layer "F.Fab")
		)
		(fp_line
			(start 0.67945 -0.3048)
			(end 0.67945 0.3048)
			(stroke
				(width 0.1)
				(type default)
			)
			(layer "F.Fab")
		)
		(fp_line
			(start 0.12065 -0.2794)
			(end 0.12065 -0.3048)
			(stroke
				(width 0.1)
				(type default)
			)
			(layer "F.Fab")
		)
		(fp_line
			(start 0.12065 -0.3048)
			(end 0.67945 -0.3048)
			(stroke
				(width 0.1)
				(type default)
			)
			(layer "F.Fab")
		)
		(fp_line
			(start 0.120396 0.3048)
			(end 0.120396 0.2794)
			(stroke
				(width 0.1)
				(type default)
			)
			(layer "F.Fab")
		)
		(fp_line
			(start 0.120396 0.2794)
			(end -0.12065 0.2794)
			(stroke
				(width 0.1)
				(type default)
			)
			(layer "F.Fab")
		)
		(fp_line
			(start -0.12065 0.3048)
			(end -0.67945 0.3048)
			(stroke
				(width 0.1)
				(type default)
			)
			(layer "F.Fab")
		)
		(fp_line
			(start -0.12065 0.2794)
			(end -0.12065 0.3048)
			(stroke
				(width 0.1)
				(type default)
			)
			(layer "F.Fab")
		)
		(fp_line
			(start -0.12065 -0.2794)
			(end 0.12065 -0.2794)
			(stroke
				(width 0.1)
				(type default)
			)
			(layer "F.Fab")
		)
		(fp_line
			(start -0.12065 -0.305054)
			(end -0.12065 -0.2794)
			(stroke
				(width 0.1)
				(type default)
			)
			(layer "F.Fab")
		)
		(fp_line
			(start -0.67945 0.3048)
			(end -0.67945 -0.305054)
			(stroke
				(width 0.1)
				(type default)
			)
			(layer "F.Fab")
		)
		(fp_line
			(start -0.67945 -0.305054)
			(end -0.12065 -0.305054)
			(stroke
				(width 0.1)
				(type default)
			)
			(layer "F.Fab")
		)
		(pad "1" smd circle
			(at -0.40005 0 180)
			(size 0 0)
			(layers "F.Cu" "F.Mask" "F.Paste")
			(net "P12V_OCP_UV_1_R")
		)
		(pad "2" smd circle
			(at 0.40005 0 180)
			(size 0 0)
			(layers "F.Cu" "F.Mask" "F.Paste")
			(net "P12V_OCP_UV_1")
		)
	)
	(footprint ""
		(layer "F.Cu")
		(at 449.692268 -72.373236 180)
		(property "Reference" "PC1867"
			(at 4.842256 -2.972562 0)
			(unlocked yes)
			(layer "F.SilkS")
			(effects
				(font
					(size 0.7874 0.5842)
					(thickness 0.1524)
				)
				(justify left)
			)
		)
		(property "Value" ""
			(at 0 0 180)
			(layer "F.Fab")
			(effects
				(font
					(size 1.27 1.27)
				)
			)
		)
		(duplicate_pad_numbers_are_jumpers no)
		(fp_line
			(start -3.400044 1.249934)
			(end 3.400044 1.249934)
			(stroke
				(width 0.1524)
				(type default)
			)
			(layer "F.SilkS")
		)
		(fp_circle
			(center 0 1.249934)
			(end -3.400044 1.249934)
			(stroke
				(width 0.1524)
				(type default)
			)
			(fill no)
			(layer "F.SilkS")
		)
		(fp_poly
			(pts
				(arc
					(start 3.400044 1.249934)
					(mid 0 4.649978)
					(end -3.400044 1.249934)
				)
			)
			(stroke
				(width 0)
				(type default)
			)
			(fill yes)
			(layer "F.SilkS")
		)
		(fp_circle
			(center 0 1.249934)
			(end -3.400044 1.249934)
			(stroke
				(width 0.1)
				(type default)
			)
			(fill no)
			(layer "F.Fab")
		)
		(pad "1" thru_hole rect
			(at 0 0 180)
			(size 1.524 1.524)
			(drill 1.016)
			(layers "*.Cu" "*.Mask")
			(remove_unused_layers no)
			(net "P3V3_AUX")
			(clearance 0)
			(padstack
				(mode front_inner_back)
				(layer "Inner"
					(shape circle)
					(size 1.524 1.524)
					(clearance 0)
				)
				(layer "B.Cu"
					(shape rect)
					(size 1.524 1.524)
					(clearance 0)
				)
			)
		)
		(pad "2" thru_hole circle
			(at 0 2.500122 180)
			(size 1.524 1.524)
			(drill 1.016)
			(layers "*.Cu" "*.Mask")
			(remove_unused_layers no)
			(net "GND")
			(clearance 0)
		)
	)
)
